# S9S_MB_2U (Grand Teton) — schematic netlist excerpt (pin names and nets, part order shuffled) for the footprints in the layout excerpt that follows; sources: Cadence DE-HDL packaged netlist, KiCad conversion of 03242023_DA0F0TMBIJ0_F0T_Motherboard_J_brd_V01_OCP.brd

C19  Q_CAP  10UF 16V 10% X6S  pkg C0805  page 87 : A = P12V_S3_AUX_CPU0_NVDIMM ; B = GND
R48  Q_RES  127K 1% CHIP  pkg 0402LF  page 104 : A = PD_CHD_CPU1_DIMM1_SAA ; B = GND
R4513  Q_RES  0 5% CHIP  pkg 0402LF  page 241 : A = SMB_HOST_3V3AUX_SDA ; B = SMB_HOST_3V3AUX_SDA_R5

(kicad_pcb
	(version 20260206)
	(generator "pcbnew")
	(generator_version "10.0")
	(general
		(thickness 1.6)
		(legacy_teardrops no)
	)
	(paper "A4")
	(title_block
		(title "03242023_DA0F0TMBIJ0_F0T_Motherboard_J_brd_V01_OCP.brd")
		(comment 1 "Grand Teton / footprints 5476-5478 of 6105")
	)
	(layers
		(0 "F.Cu" signal "TOP")
		(4 "In1.Cu" signal "GND")
		(6 "In2.Cu" signal "IN1")
		(8 "In3.Cu" signal "GND1")
		(10 "In4.Cu" signal "IN2")
		(12 "In5.Cu" signal "GND2")
		(14 "In6.Cu" signal "IN3")
		(16 "In7.Cu" signal "GND3")
		(18 "In8.Cu" signal "VCC")
		(20 "In9.Cu" signal "VCC1")
		(22 "In10.Cu" signal "GND4")
		(24 "In11.Cu" signal "IN4")
		(26 "In12.Cu" signal "GND5")
		(28 "In13.Cu" signal "IN5")
		(30 "In14.Cu" signal "GND6")
		(32 "In15.Cu" signal "IN6")
		(34 "In16.Cu" signal "GND7")
		(2 "B.Cu" signal "BOTTOM")
		(9 "F.Adhes" user "F.Adhesive")
		(11 "B.Adhes" user "B.Adhesive")
		(13 "F.Paste" user "Package Geometry/Pastemask Top")
		(15 "B.Paste" user "Package Geometry/Pastemask Bottom")
		(5 "F.SilkS" user "Ref Des/Silkscreen Top")
		(7 "B.SilkS" user "Ref Des/Silkscreen Bottom")
		(1 "F.Mask" user "Board Geometry/Soldermask Top")
		(3 "B.Mask" user "Board Geometry/Soldermask Bottom")
		(17 "Dwgs.User" user "User.Drawings")
		(19 "Cmts.User" user "User.Comments")
		(21 "Eco1.User" user "User.Eco1")
		(23 "Eco2.User" user "User.Eco2")
		(25 "Edge.Cuts" user "Board Geometry/Outline")
		(27 "Margin" user)
		(31 "F.CrtYd" user "Package Geometry/Place Bound Top")
		(29 "B.CrtYd" user "Package Geometry/Place Bound Bottom")
		(35 "F.Fab" user "Ref Des/Assembly Top")
		(33 "B.Fab" user "Ref Des/Assembly Bottom")
	)
	(footprint ""
		(layer "B.Cu")
		(at 182.245 -20.970748 180)
		(property "Reference" "R4513"
			(at 0 0 0)
			(layer "B.SilkS")
			(hide yes)
			(effects
				(font
					(size 1.27 1.27)
				)
				(justify mirror)
			)
		)
		(property "Value" ""
			(at 0 0 0)
			(layer "B.Fab")
			(effects
				(font
					(size 1.27 1.27)
				)
				(justify mirror)
			)
		)
		(duplicate_pad_numbers_are_jumpers no)
		(fp_line
			(start 0.7874 0.4064)
			(end 0.7874 -0.4064)
			(stroke
				(width 0.1524)
				(type default)
			)
			(layer "B.SilkS")
		)
		(fp_line
			(start 0.7874 -0.4064)
			(end -0.7874 -0.4064)
			(stroke
				(width 0.1524)
				(type default)
			)
			(layer "B.SilkS")
		)
		(fp_line
			(start -0.7874 0.4064)
			(end 0.7874 0.4064)
			(stroke
				(width 0.1524)
				(type default)
			)
			(layer "B.SilkS")
		)
		(fp_line
			(start -0.7874 -0.4064)
			(end -0.7874 0.4064)
			(stroke
				(width 0.1524)
				(type default)
			)
			(layer "B.SilkS")
		)
		(fp_line
			(start 0.67945 0.3048)
			(end 0.67945 -0.305054)
			(stroke
				(width 0.1)
				(type default)
			)
			(layer "B.Fab")
		)
		(fp_line
			(start 0.67945 -0.305054)
			(end 0.12065 -0.305054)
			(stroke
				(width 0.1)
				(type default)
			)
			(layer "B.Fab")
		)
		(fp_line
			(start 0.12065 0.3048)
			(end 0.67945 0.3048)
			(stroke
				(width 0.1)
				(type default)
			)
			(layer "B.Fab")
		)
		(fp_line
			(start 0.12065 0.2794)
			(end 0.12065 0.3048)
			(stroke
				(width 0.1)
				(type default)
			)
			(layer "B.Fab")
		)
		(fp_line
			(start 0.12065 -0.2794)
			(end -0.12065 -0.2794)
			(stroke
				(width 0.1)
				(type default)
			)
			(layer "B.Fab")
		)
		(fp_line
			(start 0.12065 -0.305054)
			(end 0.12065 -0.2794)
			(stroke
				(width 0.1)
				(type default)
			)
			(layer "B.Fab")
		)
		(fp_line
			(start -0.120396 0.3048)
			(end -0.120396 0.2794)
			(stroke
				(width 0.1)
				(type default)
			)
			(layer "B.Fab")
		)
		(fp_line
			(start -0.120396 0.2794)
			(end 0.12065 0.2794)
			(stroke
				(width 0.1)
				(type default)
			)
			(layer "B.Fab")
		)
		(fp_line
			(start -0.12065 -0.2794)
			(end -0.12065 -0.3048)
			(stroke
				(width 0.1)
				(type default)
			)
			(layer "B.Fab")
		)
		(fp_line
			(start -0.12065 -0.3048)
			(end -0.67945 -0.3048)
			(stroke
				(width 0.1)
				(type default)
			)
			(layer "B.Fab")
		)
		(fp_line
			(start -0.67945 0.3048)
			(end -0.120396 0.3048)
			(stroke
				(width 0.1)
				(type default)
			)
			(layer "B.Fab")
		)
		(fp_line
			(start -0.67945 -0.3048)
			(end -0.67945 0.3048)
			(stroke
				(width 0.1)
				(type default)
			)
			(layer "B.Fab")
		)
		(pad "1" smd circle
			(at 0.40005 0)
			(size 0 0)
			(layers "B.Cu" "B.Mask" "B.Paste")
			(net "SMB_HOST_3V3AUX_SDA")
		)
		(pad "2" smd circle
			(at -0.40005 0)
			(size 0 0)
			(layers "B.Cu" "B.Mask" "B.Paste")
			(net "SMB_HOST_3V3AUX_SDA_R5")
		)
	)
	(footprint ""
		(layer "B.Cu")
		(at 9.99363 -318.6176)
		(property "Reference" "R48"
			(at 0 0 0)
			(layer "B.SilkS")
			(hide yes)
			(effects
				(font
					(size 1.27 1.27)
				)
				(justify mirror)
			)
		)
		(property "Value" ""
			(at 0 0 0)
			(layer "B.Fab")
			(effects
				(font
					(size 1.27 1.27)
				)
				(justify mirror)
			)
		)
		(duplicate_pad_numbers_are_jumpers no)
		(fp_line
			(start -0.7874 -0.4064)
			(end -0.7874 0.4064)
			(stroke
				(width 0.1524)
				(type default)
			)
			(layer "B.SilkS")
		)
		(fp_line
			(start -0.7874 0.4064)
			(end 0.7874 0.4064)
			(stroke
				(width 0.1524)
				(type default)
			)
			(layer "B.SilkS")
		)
		(fp_line
			(start 0.7874 -0.4064)
			(end -0.7874 -0.4064)
			(stroke
				(width 0.1524)
				(type default)
			)
			(layer "B.SilkS")
		)
		(fp_line
			(start 0.7874 0.4064)
			(end 0.7874 -0.4064)
			(stroke
				(width 0.1524)
				(type default)
			)
			(layer "B.SilkS")
		)
		(fp_line
			(start -0.67945 -0.3048)
			(end -0.67945 0.3048)
			(stroke
				(width 0.1)
				(type default)
			)
			(layer "B.Fab")
		)
		(fp_line
			(start -0.67945 0.3048)
			(end -0.120396 0.3048)
			(stroke
				(width 0.1)
				(type default)
			)
			(layer "B.Fab")
		)
		(fp_line
			(start -0.12065 -0.3048)
			(end -0.67945 -0.3048)
			(stroke
				(width 0.1)
				(type default)
			)
			(layer "B.Fab")
		)
		(fp_line
			(start -0.12065 -0.2794)
			(end -0.12065 -0.3048)
			(stroke
				(width 0.1)
				(type default)
			)
			(layer "B.Fab")
		)
		(fp_line
			(start -0.120396 0.2794)
			(end 0.12065 0.2794)
			(stroke
				(width 0.1)
				(type default)
			)
			(layer "B.Fab")
		)
		(fp_line
			(start -0.120396 0.3048)
			(end -0.120396 0.2794)
			(stroke
				(width 0.1)
				(type default)
			)
			(layer "B.Fab")
		)
		(fp_line
			(start 0.12065 -0.305054)
			(end 0.12065 -0.2794)
			(stroke
				(width 0.1)
				(type default)
			)
			(layer "B.Fab")
		)
		(fp_line
			(start 0.12065 -0.2794)
			(end -0.12065 -0.2794)
			(stroke
				(width 0.1)
				(type default)
			)
			(layer "B.Fab")
		)
		(fp_line
			(start 0.12065 0.2794)
			(end 0.12065 0.3048)
			(stroke
				(width 0.1)
				(type default)
			)
			(layer "B.Fab")
		)
		(fp_line
			(start 0.12065 0.3048)
			(end 0.67945 0.3048)
			(stroke
				(width 0.1)
				(type default)
			)
			(layer "B.Fab")
		)
		(fp_line
			(start 0.67945 -0.305054)
			(end 0.12065 -0.305054)
			(stroke
				(width 0.1)
				(type default)
			)
			(layer "B.Fab")
		)
		(fp_line
			(start 0.67945 0.3048)
			(end 0.67945 -0.305054)
			(stroke
				(width 0.1)
				(type default)
			)
			(layer "B.Fab")
		)
		(pad "1" smd circle
			(at 0.40005 0 180)
			(size 0 0)
			(layers "B.Cu" "B.Mask" "B.Paste")
			(net "PD_CHD_CPU1_DIMM1_SAA")
		)
		(pad "2" smd circle
			(at -0.40005 0 180)
			(size 0 0)
			(layers "B.Cu" "B.Mask" "B.Paste")
			(net "GND")
		)
	)
	(footprint ""
		(layer "B.Cu")
		(at 278.724614 -321.549776 -90)
		(property "Reference" "C19"
			(at 0 0 90)
			(layer "B.SilkS")
			(hide yes)
			(effects
				(font
					(size 1.27 1.27)
				)
				(justify mirror)
			)
		)
		(property "Value" ""
			(at 0 0 90)
			(layer "B.Fab")
			(effects
				(font
					(size 1.27 1.27)
				)
				(justify mirror)
			)
		)
		(duplicate_pad_numbers_are_jumpers no)
		(fp_line
			(start -1.524 0.762)
			(end 1.524 0.762)
			(stroke
				(width 0.1524)
				(type default)
			)
			(layer "B.SilkS")
		)
		(fp_line
			(start 1.524 0.762)
			(end 1.524 -0.762)
			(stroke
				(width 0.1524)
				(type default)
			)
			(layer "B.SilkS")
		)
		(fp_line
			(start -1.524 -0.762)
			(end -1.524 0.762)
			(stroke
				(width 0.1524)
				(type default)
			)
			(layer "B.SilkS")
		)
		(fp_line
			(start 1.524 -0.762)
			(end -1.524 -0.762)
			(stroke
				(width 0.1524)
				(type default)
			)
			(layer "B.SilkS")
		)
		(fp_line
			(start -1.1049 0.724916)
			(end -1.1049 -0.724916)
			(stroke
				(width 0.1)
				(type default)
			)
			(layer "B.Fab")
		)
		(fp_line
			(start 1.1049 0.724916)
			(end -1.1049 0.724916)
			(stroke
				(width 0.1)
				(type default)
			)
			(layer "B.Fab")
		)
		(fp_line
			(start -1.1049 -0.724916)
			(end 1.1049 -0.724916)
			(stroke
				(width 0.1)
				(type default)
			)
			(layer "B.Fab")
		)
		(fp_line
			(start 1.1049 -0.724916)
			(end 1.1049 0.724916)
			(stroke
				(width 0.1)
				(type default)
			)
			(layer "B.Fab")
		)
		(pad "1" smd rect
			(at 0.889 0 270)
			(size 1.016 1.27)
			(layers "B.Cu" "B.Mask" "B.Paste")
			(net "P12V_S3_AUX_CPU0_NVDIMM")
		)
		(pad "2" smd rect
			(at -0.889 0 270)
			(size 1.016 1.27)
			(layers "B.Cu" "B.Mask" "B.Paste")
			(net "GND")
		)
	)
)
